(kicad_pcb
	(version 20260206)
	(generator "pcbnew")
	(generator_version "10.0")
	(general
		(thickness 1.6)
		(legacy_teardrops no)
	)
	(paper "A4")
	(title_block
		(title "Wiwynn_Tioga_Pass_MB.brd")
		(comment 1 "Tioga Pass / footprints 4651-4657 of 4770")
	)
	(layers
		(0 "F.Cu" signal "TOP")
		(4 "In1.Cu" signal "L2GND")
		(6 "In2.Cu" signal "L3")
		(8 "In3.Cu" signal "L4GND")
		(10 "In4.Cu" signal "L5")
		(12 "In5.Cu" signal "L6GND")
		(14 "In6.Cu" signal "L7VCC")
		(16 "In7.Cu" signal "L8VCC")
		(18 "In8.Cu" signal "L9GND")
		(20 "In9.Cu" signal "L10")
		(22 "In10.Cu" signal "L11GND")
		(24 "In11.Cu" signal "L12")
		(26 "In12.Cu" signal "L13GND")
		(2 "B.Cu" signal "BOTTOM")
		(9 "F.Adhes" user "F.Adhesive")
		(11 "B.Adhes" user "B.Adhesive")
		(13 "F.Paste" user "Package Geometry/Pastemask Top")
		(15 "B.Paste" user "Package Geometry/Pastemask Bottom")
		(5 "F.SilkS" user "Ref Des/Silkscreen Top")
		(7 "B.SilkS" user "Ref Des/Silkscreen Bottom")
		(1 "F.Mask" user "Board Geometry/Soldermask Top")
		(3 "B.Mask" user "Board Geometry/Soldermask Bottom")
		(17 "Dwgs.User" user "User.Drawings")
		(19 "Cmts.User" user "User.Comments")
		(21 "Eco1.User" user "User.Eco1")
		(23 "Eco2.User" user "User.Eco2")
		(25 "Edge.Cuts" user "Board Geometry/Outline")
		(27 "Margin" user)
		(31 "F.CrtYd" user "Package Geometry/Place Bound Top")
		(29 "B.CrtYd" user "Package Geometry/Place Bound Bottom")
		(35 "F.Fab" user "Ref Des/Assembly Top")
		(33 "B.Fab" user "Ref Des/Assembly Bottom")
	)
	(footprint ""
		(layer "B.Cu")
		(at 276.000464 -8.1534 90)
		(property "Reference" "C5U2"
			(at -1.848866 0.752348 90)
			(unlocked yes)
			(layer "B.SilkS")
			(effects
				(font
					(size 1.27 0.9652)
					(thickness 0.1524)
				)
				(justify mirror)
			)
		)
		(property "Value" ""
			(at 0 0 90)
			(layer "B.Fab")
			(effects
				(font
					(size 1.27 1.27)
				)
				(justify mirror)
			)
		)
		(duplicate_pad_numbers_are_jumpers no)
		(fp_rect
			(start 0.500126 1.598422)
			(end -0.500126 -0.201422)
			(stroke
				(width 0)
				(type default)
			)
			(fill no)
			(layer "B.CrtYd")
		)
		(fp_line
			(start 0.500126 -0.201422)
			(end -0.500126 -0.201422)
			(stroke
				(width 0.1)
				(type default)
			)
			(layer "B.Fab")
		)
		(fp_line
			(start -0.500126 -0.201422)
			(end -0.500126 1.598422)
			(stroke
				(width 0.1)
				(type default)
			)
			(layer "B.Fab")
		)
		(fp_line
			(start 0.500126 1.598422)
			(end 0.500126 -0.201422)
			(stroke
				(width 0.1)
				(type default)
			)
			(layer "B.Fab")
		)
		(fp_line
			(start -0.500126 1.598422)
			(end 0.500126 1.598422)
			(stroke
				(width 0.1)
				(type default)
			)
			(layer "B.Fab")
		)
		(pad "1" smd rect
			(at 0 0)
			(size 0.889 0.9906)
			(layers "B.Cu" "B.Mask" "B.Paste")
			(net "PVDDQ_ABC")
		)
		(pad "2" smd rect
			(at 0 1.397)
			(size 0.889 0.9906)
			(layers "B.Cu" "B.Mask" "B.Paste")
			(net "GND")
		)
		(zone
			(layer "B.Cu")
			(hatch none 0.5)
			(connect_pads
				(clearance 0)
			)
			(min_thickness 0.25)
			(keepout
				(tracks allowed)
				(vias not_allowed)
				(pads allowed)
				(copperpour not_allowed)
				(footprints allowed)
			)
			(placement
				(enabled no)
				(sheetname "")
			)
			(fill
				(thermal_gap 0.5)
				(thermal_bridge_width 0.5)
				(island_removal_mode 0)
			)
			(polygon
				(pts
					(xy 276.952964 -8.6487) (xy 276.444964 -8.6487) (xy 276.444964 -7.6581) (xy 276.952964 -7.6581)
				)
			)
		)
		(zone
			(layer "B.Cu")
			(hatch none 0.5)
			(connect_pads
				(clearance 0)
			)
			(min_thickness 0.25)
			(keepout
				(tracks not_allowed)
				(vias allowed)
				(pads allowed)
				(copperpour not_allowed)
				(footprints allowed)
			)
			(placement
				(enabled no)
				(sheetname "")
			)
			(fill
				(thermal_gap 0.5)
				(thermal_bridge_width 0.5)
				(island_removal_mode 0)
			)
			(polygon
				(pts
					(xy 276.952964 -8.6487) (xy 276.444964 -8.6487) (xy 276.444964 -7.6581) (xy 276.952964 -7.6581)
				)
			)
		)
	)
	(footprint ""
		(layer "B.Cu")
		(at 153.797 1.7018 -90)
		(property "Reference" "C7U6"
			(at 0 0 90)
			(layer "B.SilkS")
			(hide yes)
			(effects
				(font
					(size 1.27 1.27)
				)
				(justify mirror)
			)
		)
		(property "Value" ""
			(at 0 0 90)
			(layer "B.Fab")
			(effects
				(font
					(size 1.27 1.27)
				)
				(justify mirror)
			)
		)
		(duplicate_pad_numbers_are_jumpers no)
		(fp_poly
			(pts
				(xy 0.4953 -0.2032) (xy -0.4953 -0.2032) (xy -0.4953 1.6002) (xy 0.4953 1.6002)
			)
			(stroke
				(width 0)
				(type default)
			)
			(fill no)
			(layer "B.CrtYd")
		)
		(fp_line
			(start -0.4953 1.6002)
			(end 0.4953 1.6002)
			(stroke
				(width 0.1)
				(type default)
			)
			(layer "B.Fab")
		)
		(fp_line
			(start 0.4953 1.6002)
			(end 0.4953 -0.2032)
			(stroke
				(width 0.1)
				(type default)
			)
			(layer "B.Fab")
		)
		(fp_line
			(start -0.4953 -0.2032)
			(end -0.4953 1.6002)
			(stroke
				(width 0.1)
				(type default)
			)
			(layer "B.Fab")
		)
		(fp_line
			(start 0.4953 -0.2032)
			(end -0.4953 -0.2032)
			(stroke
				(width 0.1)
				(type default)
			)
			(layer "B.Fab")
		)
		(pad "1" smd rect
			(at 0 0 90)
			(size 0.762 0.889)
			(layers "B.Cu" "B.Mask" "B.Paste")
			(net "PVPP_GHJ")
		)
		(pad "2" smd rect
			(at 0 1.397 90)
			(size 0.762 0.889)
			(layers "B.Cu" "B.Mask" "B.Paste")
			(net "GND")
		)
		(zone
			(layer "B.Cu")
			(hatch none 0.5)
			(connect_pads
				(clearance 0)
			)
			(min_thickness 0.25)
			(keepout
				(tracks not_allowed)
				(vias allowed)
				(pads allowed)
				(copperpour not_allowed)
				(footprints allowed)
			)
			(placement
				(enabled no)
				(sheetname "")
			)
			(fill
				(thermal_gap 0.5)
				(thermal_bridge_width 0.5)
				(island_removal_mode 0)
			)
			(polygon
				(pts
					(xy 153.3525 2.0828) (xy 153.3525 1.3208) (xy 152.8445 1.3208) (xy 152.8445 2.0828)
				)
			)
		)
	)
	(footprint ""
		(layer "B.Cu")
		(at 450.215 -116.49202)
		(property "Reference" "C1M16"
			(at 0 0 0)
			(layer "B.SilkS")
			(hide yes)
			(effects
				(font
					(size 1.27 1.27)
				)
				(justify mirror)
			)
		)
		(property "Value" ""
			(at 0 0 0)
			(layer "B.Fab")
			(effects
				(font
					(size 1.27 1.27)
				)
				(justify mirror)
			)
		)
		(duplicate_pad_numbers_are_jumpers no)
		(fp_rect
			(start -0.3048 0.9906)
			(end 0.3048 -0.1016)
			(stroke
				(width 0)
				(type default)
			)
			(fill no)
			(layer "B.CrtYd")
		)
		(fp_line
			(start -0.3048 -0.1016)
			(end 0.3048 -0.1016)
			(stroke
				(width 0.1)
				(type default)
			)
			(layer "B.Fab")
		)
		(fp_line
			(start -0.3048 0.9906)
			(end -0.3048 -0.1016)
			(stroke
				(width 0.1)
				(type default)
			)
			(layer "B.Fab")
		)
		(fp_line
			(start 0.3048 -0.1016)
			(end 0.3048 0.9906)
			(stroke
				(width 0.1)
				(type default)
			)
			(layer "B.Fab")
		)
		(fp_line
			(start 0.3048 0.9906)
			(end -0.3048 0.9906)
			(stroke
				(width 0.1)
				(type default)
			)
			(layer "B.Fab")
		)
		(pad "1" smd rect
			(at 0 0 180)
			(size 0.508 0.508)
			(layers "B.Cu" "B.Mask" "B.Paste")
			(net "P3E_CPU0_PE3_OCP_TXP<10>")
		)
		(pad "2" smd rect
			(at 0 0.889 180)
			(size 0.508 0.508)
			(layers "B.Cu" "B.Mask" "B.Paste")
			(net "P3E_OCP_CPU0_PE3_C_TXP<10>")
		)
		(zone
			(layer "B.Cu")
			(hatch none 0.5)
			(connect_pads
				(clearance 0)
			)
			(min_thickness 0.25)
			(keepout
				(tracks not_allowed)
				(vias allowed)
				(pads allowed)
				(copperpour not_allowed)
				(footprints allowed)
			)
			(placement
				(enabled no)
				(sheetname "")
			)
			(fill
				(thermal_gap 0.5)
				(thermal_bridge_width 0.5)
				(island_removal_mode 0)
			)
			(polygon
				(pts
					(xy 449.961 -115.85702) (xy 450.469 -115.85702) (xy 450.469 -116.23802) (xy 449.961 -116.23802)
				)
			)
		)
		(zone
			(layer "B.Cu")
			(hatch none 0.5)
			(connect_pads
				(clearance 0)
			)
			(min_thickness 0.25)
			(keepout
				(tracks allowed)
				(vias not_allowed)
				(pads allowed)
				(copperpour not_allowed)
				(footprints allowed)
			)
			(placement
				(enabled no)
				(sheetname "")
			)
			(fill
				(thermal_gap 0.5)
				(thermal_bridge_width 0.5)
				(island_removal_mode 0)
			)
			(polygon
				(pts
					(xy 449.961 -115.85702) (xy 450.469 -115.85702) (xy 450.469 -116.23802) (xy 449.961 -116.23802)
				)
			)
		)
	)
	(footprint ""
		(layer "B.Cu")
		(at 348.2086 -8.8138 -90)
		(property "Reference" "R3U6"
			(at 0 0 90)
			(layer "B.SilkS")
			(hide yes)
			(effects
				(font
					(size 1.27 1.27)
				)
				(justify mirror)
			)
		)
		(property "Value" ""
			(at 0 0 90)
			(layer "B.Fab")
			(effects
				(font
					(size 1.27 1.27)
				)
				(justify mirror)
			)
		)
		(duplicate_pad_numbers_are_jumpers no)
		(fp_rect
			(start -0.2794 0.9906)
			(end 0.2794 -0.1016)
			(stroke
				(width 0)
				(type default)
			)
			(fill no)
			(layer "B.CrtYd")
		)
		(fp_line
			(start -0.2794 0.9906)
			(end -0.2794 -0.1016)
			(stroke
				(width 0.1)
				(type default)
			)
			(layer "B.Fab")
		)
		(fp_line
			(start 0.2794 0.9906)
			(end -0.2794 0.9906)
			(stroke
				(width 0.1)
				(type default)
			)
			(layer "B.Fab")
		)
		(fp_line
			(start -0.2794 -0.1016)
			(end 0.2794 -0.1016)
			(stroke
				(width 0.1)
				(type default)
			)
			(layer "B.Fab")
		)
		(fp_line
			(start 0.2794 -0.1016)
			(end 0.2794 0.9906)
			(stroke
				(width 0.1)
				(type default)
			)
			(layer "B.Fab")
		)
		(pad "1" smd rect
			(at 0 0 90)
			(size 0.508 0.508)
			(layers "B.Cu" "B.Mask" "B.Paste")
			(net "VR_PVDDQ_ABC_PH1_VCIN")
		)
		(pad "2" smd rect
			(at 0 0.889 90)
			(size 0.508 0.508)
			(layers "B.Cu" "B.Mask" "B.Paste")
			(net "P5V_STBY")
		)
		(zone
			(layer "B.Cu")
			(hatch none 0.5)
			(connect_pads
				(clearance 0)
			)
			(min_thickness 0.25)
			(keepout
				(tracks not_allowed)
				(vias allowed)
				(pads allowed)
				(copperpour not_allowed)
				(footprints allowed)
			)
			(placement
				(enabled no)
				(sheetname "")
			)
			(fill
				(thermal_gap 0.5)
				(thermal_bridge_width 0.5)
				(island_removal_mode 0)
			)
			(polygon
				(pts
					(xy 347.5736 -9.0678) (xy 347.5736 -8.5598) (xy 347.9546 -8.5598) (xy 347.9546 -9.0678)
				)
			)
		)
		(zone
			(layer "B.Cu")
			(hatch none 0.5)
			(connect_pads
				(clearance 0)
			)
			(min_thickness 0.25)
			(keepout
				(tracks allowed)
				(vias not_allowed)
				(pads allowed)
				(copperpour not_allowed)
				(footprints allowed)
			)
			(placement
				(enabled no)
				(sheetname "")
			)
			(fill
				(thermal_gap 0.5)
				(thermal_bridge_width 0.5)
				(island_removal_mode 0)
			)
			(polygon
				(pts
					(xy 347.5736 -9.0678) (xy 347.5736 -8.5598) (xy 347.9546 -8.5598) (xy 347.9546 -9.0678)
				)
			)
		)
	)
	(footprint ""
		(layer "B.Cu")
		(at 168.0972 -7.366)
		(property "Reference" "R6U3"
			(at 0 0 0)
			(layer "B.SilkS")
			(hide yes)
			(effects
				(font
					(size 1.27 1.27)
				)
				(justify mirror)
			)
		)
		(property "Value" ""
			(at 0 0 0)
			(layer "B.Fab")
			(effects
				(font
					(size 1.27 1.27)
				)
				(justify mirror)
			)
		)
		(duplicate_pad_numbers_are_jumpers no)
		(fp_rect
			(start -0.2794 -0.1016)
			(end 0.2794 0.9906)
			(stroke
				(width 0)
				(type default)
			)
			(fill no)
			(layer "B.CrtYd")
		)
		(fp_line
			(start -0.2794 -0.1016)
			(end 0.2794 -0.1016)
			(stroke
				(width 0.1)
				(type default)
			)
			(layer "B.Fab")
		)
		(fp_line
			(start -0.2794 0.9906)
			(end -0.2794 -0.1016)
			(stroke
				(width 0.1)
				(type default)
			)
			(layer "B.Fab")
		)
		(fp_line
			(start 0.2794 -0.1016)
			(end 0.2794 0.9906)
			(stroke
				(width 0.1)
				(type default)
			)
			(layer "B.Fab")
		)
		(fp_line
			(start 0.2794 0.9906)
			(end -0.2794 0.9906)
			(stroke
				(width 0.1)
				(type default)
			)
			(layer "B.Fab")
		)
		(pad "1" smd rect
			(at 0 0 180)
			(size 0.508 0.508)
			(layers "B.Cu" "B.Mask" "B.Paste")
			(net "P3V3")
		)
		(pad "2" smd rect
			(at 0 0.889 180)
			(size 0.508 0.508)
			(layers "B.Cu" "B.Mask" "B.Paste")
			(net "FM_PVTT_GHJ_EN_R")
		)
		(zone
			(layer "B.Cu")
			(hatch none 0.5)
			(connect_pads
				(clearance 0)
			)
			(min_thickness 0.25)
			(keepout
				(tracks not_allowed)
				(vias allowed)
				(pads allowed)
				(copperpour not_allowed)
				(footprints allowed)
			)
			(placement
				(enabled no)
				(sheetname "")
			)
			(fill
				(thermal_gap 0.5)
				(thermal_bridge_width 0.5)
				(island_removal_mode 0)
			)
			(polygon
				(pts
					(xy 167.8432 -7.112) (xy 167.8432 -6.731) (xy 168.3512 -6.731) (xy 168.3512 -7.112)
				)
			)
		)
		(zone
			(layer "B.Cu")
			(hatch none 0.5)
			(connect_pads
				(clearance 0)
			)
			(min_thickness 0.25)
			(keepout
				(tracks allowed)
				(vias not_allowed)
				(pads allowed)
				(copperpour not_allowed)
				(footprints allowed)
			)
			(placement
				(enabled no)
				(sheetname "")
			)
			(fill
				(thermal_gap 0.5)
				(thermal_bridge_width 0.5)
				(island_removal_mode 0)
			)
			(polygon
				(pts
					(xy 167.8432 -7.112) (xy 167.8432 -6.731) (xy 168.3512 -6.731) (xy 168.3512 -7.112)
				)
			)
		)
	)
	(footprint ""
		(layer "B.Cu")
		(at 411.099 -142.0368 -90)
		(property "Reference" "C2L38"
			(at 0 0 90)
			(layer "B.SilkS")
			(hide yes)
			(effects
				(font
					(size 1.27 1.27)
				)
				(justify mirror)
			)
		)
		(property "Value" ""
			(at 0 0 90)
			(layer "B.Fab")
			(effects
				(font
					(size 1.27 1.27)
				)
				(justify mirror)
			)
		)
		(duplicate_pad_numbers_are_jumpers no)
		(fp_poly
			(pts
				(xy -0.3048 -0.1016) (xy -0.3048 0.9906) (xy 0.3048 0.9906) (xy 0.3048 -0.1016)
			)
			(stroke
				(width 0)
				(type default)
			)
			(fill no)
			(layer "B.CrtYd")
		)
		(fp_line
			(start -0.3048 0.9906)
			(end -0.3048 -0.1016)
			(stroke
				(width 0.1)
				(type default)
			)
			(layer "B.Fab")
		)
		(fp_line
			(start 0.3048 0.9906)
			(end -0.3048 0.9906)
			(stroke
				(width 0.1)
				(type default)
			)
			(layer "B.Fab")
		)
		(fp_line
			(start -0.3048 -0.1016)
			(end 0.3048 -0.1016)
			(stroke
				(width 0.1)
				(type default)
			)
			(layer "B.Fab")
		)
		(fp_line
			(start 0.3048 -0.1016)
			(end 0.3048 0.9906)
			(stroke
				(width 0.1)
				(type default)
			)
			(layer "B.Fab")
		)
		(pad "1" smd rect
			(at 0 0 90)
			(size 0.508 0.508)
			(layers "B.Cu" "B.Mask" "B.Paste")
			(net "SATA6G_P6_TX_C_DN")
		)
		(pad "2" smd rect
			(at 0 0.889 90)
			(size 0.508 0.508)
			(layers "B.Cu" "B.Mask" "B.Paste")
			(net "SATA6G_PCH_PCIE_UP_SATA_TXN<6>")
		)
		(zone
			(layer "B.Cu")
			(hatch none 0.5)
			(connect_pads
				(clearance 0)
			)
			(min_thickness 0.25)
			(keepout
				(tracks not_allowed)
				(vias allowed)
				(pads allowed)
				(copperpour not_allowed)
				(footprints allowed)
			)
			(placement
				(enabled no)
				(sheetname "")
			)
			(fill
				(thermal_gap 0.5)
				(thermal_bridge_width 0.5)
				(island_removal_mode 0)
			)
			(polygon
				(pts
					(xy 410.464 -141.7828) (xy 410.464 -142.2908) (xy 410.845 -142.2908) (xy 410.845 -141.7828)
				)
			)
		)
		(zone
			(layer "B.Cu")
			(hatch none 0.5)
			(connect_pads
				(clearance 0)
			)
			(min_thickness 0.25)
			(keepout
				(tracks allowed)
				(vias not_allowed)
				(pads allowed)
				(copperpour not_allowed)
				(footprints allowed)
			)
			(placement
				(enabled no)
				(sheetname "")
			)
			(fill
				(thermal_gap 0.5)
				(thermal_bridge_width 0.5)
				(island_removal_mode 0)
			)
			(polygon
				(pts
					(xy 410.845 -141.7828) (xy 410.845 -142.2908) (xy 410.464 -142.2908) (xy 410.464 -141.7828)
				)
			)
		)
	)
	(footprint ""
		(layer "B.Cu")
		(at 111.000032 -8.1534 90)
		(property "Reference" "C7U1"
			(at -1.848866 0.752348 90)
			(unlocked yes)
			(layer "B.SilkS")
			(effects
				(font
					(size 1.27 0.9652)
					(thickness 0.1524)
				)
				(justify mirror)
			)
		)
		(property "Value" ""
			(at 0 0 90)
			(layer "B.Fab")
			(effects
				(font
					(size 1.27 1.27)
				)
				(justify mirror)
			)
		)
		(duplicate_pad_numbers_are_jumpers no)
		(fp_rect
			(start 0.500126 1.598422)
			(end -0.500126 -0.201422)
			(stroke
				(width 0)
				(type default)
			)
			(fill no)
			(layer "B.CrtYd")
		)
		(fp_line
			(start 0.500126 -0.201422)
			(end -0.500126 -0.201422)
			(stroke
				(width 0.1)
				(type default)
			)
			(layer "B.Fab")
		)
		(fp_line
			(start -0.500126 -0.201422)
			(end -0.500126 1.598422)
			(stroke
				(width 0.1)
				(type default)
			)
			(layer "B.Fab")
		)
		(fp_line
			(start 0.500126 1.598422)
			(end 0.500126 -0.201422)
			(stroke
				(width 0.1)
				(type default)
			)
			(layer "B.Fab")
		)
		(fp_line
			(start -0.500126 1.598422)
			(end 0.500126 1.598422)
			(stroke
				(width 0.1)
				(type default)
			)
			(layer "B.Fab")
		)
		(pad "1" smd rect
			(at 0 0)
			(size 0.889 0.9906)
			(layers "B.Cu" "B.Mask" "B.Paste")
			(net "PVDDQ_GHJ")
		)
		(pad "2" smd rect
			(at 0 1.397)
			(size 0.889 0.9906)
			(layers "B.Cu" "B.Mask" "B.Paste")
			(net "GND")
		)
		(zone
			(layer "B.Cu")
			(hatch none 0.5)
			(connect_pads
				(clearance 0)
			)
			(min_thickness 0.25)
			(keepout
				(tracks not_allowed)
				(vias allowed)
				(pads allowed)
				(copperpour not_allowed)
				(footprints allowed)
			)
			(placement
				(enabled no)
				(sheetname "")
			)
			(fill
				(thermal_gap 0.5)
				(thermal_bridge_width 0.5)
				(island_removal_mode 0)
			)
			(polygon
				(pts
					(xy 111.952532 -8.6487) (xy 111.444532 -8.6487) (xy 111.444532 -7.6581) (xy 111.952532 -7.6581)
				)
			)
		)
		(zone
			(layer "B.Cu")
			(hatch none 0.5)
			(connect_pads
				(clearance 0)
			)
			(min_thickness 0.25)
			(keepout
				(tracks allowed)
				(vias not_allowed)
				(pads allowed)
				(copperpour not_allowed)
				(footprints allowed)
			)
			(placement
				(enabled no)
				(sheetname "")
			)
			(fill
				(thermal_gap 0.5)
				(thermal_bridge_width 0.5)
				(island_removal_mode 0)
			)
			(polygon
				(pts
					(xy 111.952532 -8.6487) (xy 111.444532 -8.6487) (xy 111.444532 -7.6581) (xy 111.952532 -7.6581)
				)
			)
		)
	)
)
